# S9S_MB_2U (Grand Teton) — schematic netlist excerpt (pin names and nets, part order shuffled) for the footprints in the layout excerpt that follows; sources: Cadence DE-HDL packaged netlist, KiCad conversion of 03242023_DA0F0TMBIJ0_F0T_Motherboard_J_brd_V01_OCP.brd

C367  Q_CAP  47UF 4V 20% X6S  pkg C0805  page 75 : A = PVCCIN_CPU0 ; B = GND
PR637  Q_RES  10K 1% EMPTY  pkg 0402LF  page 284 : A = PVCCIN_CPU1_ATSEN ; B = GND
PR296  Q_RES  0 5% CHIP  pkg 0402LF  page 287 : A = PVCCIN_CPU1_VOS5 ; B = PVCCIN_CPU1

(kicad_pcb
	(version 20260206)
	(generator "pcbnew")
	(generator_version "10.0")
	(general
		(thickness 1.6)
		(legacy_teardrops no)
	)
	(paper "A4")
	(title_block
		(title "03242023_DA0F0TMBIJ0_F0T_Motherboard_J_brd_V01_OCP.brd")
		(comment 1 "Grand Teton / footprints 5224-5226 of 6105")
	)
	(layers
		(0 "F.Cu" signal "TOP")
		(4 "In1.Cu" signal "GND")
		(6 "In2.Cu" signal "IN1")
		(8 "In3.Cu" signal "GND1")
		(10 "In4.Cu" signal "IN2")
		(12 "In5.Cu" signal "GND2")
		(14 "In6.Cu" signal "IN3")
		(16 "In7.Cu" signal "GND3")
		(18 "In8.Cu" signal "VCC")
		(20 "In9.Cu" signal "VCC1")
		(22 "In10.Cu" signal "GND4")
		(24 "In11.Cu" signal "IN4")
		(26 "In12.Cu" signal "GND5")
		(28 "In13.Cu" signal "IN5")
		(30 "In14.Cu" signal "GND6")
		(32 "In15.Cu" signal "IN6")
		(34 "In16.Cu" signal "GND7")
		(2 "B.Cu" signal "BOTTOM")
		(9 "F.Adhes" user "F.Adhesive")
		(11 "B.Adhes" user "B.Adhesive")
		(13 "F.Paste" user "Package Geometry/Pastemask Top")
		(15 "B.Paste" user "Package Geometry/Pastemask Bottom")
		(5 "F.SilkS" user "Ref Des/Silkscreen Top")
		(7 "B.SilkS" user "Ref Des/Silkscreen Bottom")
		(1 "F.Mask" user "Board Geometry/Soldermask Top")
		(3 "B.Mask" user "Board Geometry/Soldermask Bottom")
		(17 "Dwgs.User" user "User.Drawings")
		(19 "Cmts.User" user "User.Comments")
		(21 "Eco1.User" user "User.Eco1")
		(23 "Eco2.User" user "User.Eco2")
		(25 "Edge.Cuts" user "Board Geometry/Outline")
		(27 "Margin" user)
		(31 "F.CrtYd" user "Package Geometry/Place Bound Top")
		(29 "B.CrtYd" user "Package Geometry/Place Bound Bottom")
		(35 "F.Fab" user "Ref Des/Assembly Top")
		(33 "B.Fab" user "Ref Des/Assembly Bottom")
	)
	(footprint ""
		(layer "B.Cu")
		(at 114.693446 -358.566212 180)
		(property "Reference" "PR637"
			(at 0 0 0)
			(layer "B.SilkS")
			(hide yes)
			(effects
				(font
					(size 1.27 1.27)
				)
				(justify mirror)
			)
		)
		(property "Value" ""
			(at 0 0 0)
			(layer "B.Fab")
			(effects
				(font
					(size 1.27 1.27)
				)
				(justify mirror)
			)
		)
		(duplicate_pad_numbers_are_jumpers no)
		(fp_line
			(start 0.7874 0.4064)
			(end 0.7874 -0.4064)
			(stroke
				(width 0.1524)
				(type default)
			)
			(layer "B.SilkS")
		)
		(fp_line
			(start 0.7874 -0.4064)
			(end -0.7874 -0.4064)
			(stroke
				(width 0.1524)
				(type default)
			)
			(layer "B.SilkS")
		)
		(fp_line
			(start -0.7874 0.4064)
			(end 0.7874 0.4064)
			(stroke
				(width 0.1524)
				(type default)
			)
			(layer "B.SilkS")
		)
		(fp_line
			(start -0.7874 -0.4064)
			(end -0.7874 0.4064)
			(stroke
				(width 0.1524)
				(type default)
			)
			(layer "B.SilkS")
		)
		(fp_line
			(start 0.67945 0.3048)
			(end 0.67945 -0.305054)
			(stroke
				(width 0.1)
				(type default)
			)
			(layer "B.Fab")
		)
		(fp_line
			(start 0.67945 -0.305054)
			(end 0.12065 -0.305054)
			(stroke
				(width 0.1)
				(type default)
			)
			(layer "B.Fab")
		)
		(fp_line
			(start 0.12065 0.3048)
			(end 0.67945 0.3048)
			(stroke
				(width 0.1)
				(type default)
			)
			(layer "B.Fab")
		)
		(fp_line
			(start 0.12065 0.2794)
			(end 0.12065 0.3048)
			(stroke
				(width 0.1)
				(type default)
			)
			(layer "B.Fab")
		)
		(fp_line
			(start 0.12065 -0.2794)
			(end -0.12065 -0.2794)
			(stroke
				(width 0.1)
				(type default)
			)
			(layer "B.Fab")
		)
		(fp_line
			(start 0.12065 -0.305054)
			(end 0.12065 -0.2794)
			(stroke
				(width 0.1)
				(type default)
			)
			(layer "B.Fab")
		)
		(fp_line
			(start -0.120396 0.3048)
			(end -0.120396 0.2794)
			(stroke
				(width 0.1)
				(type default)
			)
			(layer "B.Fab")
		)
		(fp_line
			(start -0.120396 0.2794)
			(end 0.12065 0.2794)
			(stroke
				(width 0.1)
				(type default)
			)
			(layer "B.Fab")
		)
		(fp_line
			(start -0.12065 -0.2794)
			(end -0.12065 -0.3048)
			(stroke
				(width 0.1)
				(type default)
			)
			(layer "B.Fab")
		)
		(fp_line
			(start -0.12065 -0.3048)
			(end -0.67945 -0.3048)
			(stroke
				(width 0.1)
				(type default)
			)
			(layer "B.Fab")
		)
		(fp_line
			(start -0.67945 0.3048)
			(end -0.120396 0.3048)
			(stroke
				(width 0.1)
				(type default)
			)
			(layer "B.Fab")
		)
		(fp_line
			(start -0.67945 -0.3048)
			(end -0.67945 0.3048)
			(stroke
				(width 0.1)
				(type default)
			)
			(layer "B.Fab")
		)
		(pad "1" smd circle
			(at 0.40005 0)
			(size 0 0)
			(layers "B.Cu" "B.Mask" "B.Paste")
			(net "PVCCIN_CPU1_ATSEN")
		)
		(pad "2" smd circle
			(at -0.40005 0)
			(size 0 0)
			(layers "B.Cu" "B.Mask" "B.Paste")
			(net "GND")
		)
	)
	(footprint ""
		(layer "B.Cu")
		(at 126.065026 -339.602572 -90)
		(property "Reference" "PR296"
			(at 0 0 90)
			(layer "B.SilkS")
			(hide yes)
			(effects
				(font
					(size 1.27 1.27)
				)
				(justify mirror)
			)
		)
		(property "Value" ""
			(at 0 0 90)
			(layer "B.Fab")
			(effects
				(font
					(size 1.27 1.27)
				)
				(justify mirror)
			)
		)
		(duplicate_pad_numbers_are_jumpers no)
		(fp_line
			(start -0.7874 0.4064)
			(end 0.7874 0.4064)
			(stroke
				(width 0.1524)
				(type default)
			)
			(layer "B.SilkS")
		)
		(fp_line
			(start 0.7874 0.4064)
			(end 0.7874 -0.4064)
			(stroke
				(width 0.1524)
				(type default)
			)
			(layer "B.SilkS")
		)
		(fp_line
			(start -0.7874 -0.4064)
			(end -0.7874 0.4064)
			(stroke
				(width 0.1524)
				(type default)
			)
			(layer "B.SilkS")
		)
		(fp_line
			(start 0.7874 -0.4064)
			(end -0.7874 -0.4064)
			(stroke
				(width 0.1524)
				(type default)
			)
			(layer "B.SilkS")
		)
		(fp_line
			(start -0.67945 0.3048)
			(end -0.120396 0.3048)
			(stroke
				(width 0.1)
				(type default)
			)
			(layer "B.Fab")
		)
		(fp_line
			(start -0.120396 0.3048)
			(end -0.120396 0.2794)
			(stroke
				(width 0.1)
				(type default)
			)
			(layer "B.Fab")
		)
		(fp_line
			(start 0.12065 0.3048)
			(end 0.67945 0.3048)
			(stroke
				(width 0.1)
				(type default)
			)
			(layer "B.Fab")
		)
		(fp_line
			(start 0.67945 0.3048)
			(end 0.67945 -0.305054)
			(stroke
				(width 0.1)
				(type default)
			)
			(layer "B.Fab")
		)
		(fp_line
			(start -0.120396 0.2794)
			(end 0.12065 0.2794)
			(stroke
				(width 0.1)
				(type default)
			)
			(layer "B.Fab")
		)
		(fp_line
			(start 0.12065 0.2794)
			(end 0.12065 0.3048)
			(stroke
				(width 0.1)
				(type default)
			)
			(layer "B.Fab")
		)
		(fp_line
			(start -0.12065 -0.2794)
			(end -0.12065 -0.3048)
			(stroke
				(width 0.1)
				(type default)
			)
			(layer "B.Fab")
		)
		(fp_line
			(start 0.12065 -0.2794)
			(end -0.12065 -0.2794)
			(stroke
				(width 0.1)
				(type default)
			)
			(layer "B.Fab")
		)
		(fp_line
			(start -0.67945 -0.3048)
			(end -0.67945 0.3048)
			(stroke
				(width 0.1)
				(type default)
			)
			(layer "B.Fab")
		)
		(fp_line
			(start -0.12065 -0.3048)
			(end -0.67945 -0.3048)
			(stroke
				(width 0.1)
				(type default)
			)
			(layer "B.Fab")
		)
		(fp_line
			(start 0.12065 -0.305054)
			(end 0.12065 -0.2794)
			(stroke
				(width 0.1)
				(type default)
			)
			(layer "B.Fab")
		)
		(fp_line
			(start 0.67945 -0.305054)
			(end 0.12065 -0.305054)
			(stroke
				(width 0.1)
				(type default)
			)
			(layer "B.Fab")
		)
		(pad "1" smd circle
			(at 0.40005 0 90)
			(size 0 0)
			(layers "B.Cu" "B.Mask" "B.Paste")
			(net "PVCCIN_CPU1_VOS5")
		)
		(pad "2" smd circle
			(at -0.40005 0 90)
			(size 0 0)
			(layers "B.Cu" "B.Mask" "B.Paste")
			(net "PVCCIN_CPU1")
		)
	)
	(footprint ""
		(layer "B.Cu")
		(at 366.120934 -252.176026 -90)
		(property "Reference" "C367"
			(at 0 0 90)
			(layer "B.SilkS")
			(hide yes)
			(effects
				(font
					(size 1.27 1.27)
				)
				(justify mirror)
			)
		)
		(property "Value" ""
			(at 0 0 90)
			(layer "B.Fab")
			(effects
				(font
					(size 1.27 1.27)
				)
				(justify mirror)
			)
		)
		(duplicate_pad_numbers_are_jumpers no)
		(fp_line
			(start -1.524 0.762)
			(end 1.524 0.762)
			(stroke
				(width 0.1524)
				(type default)
			)
			(layer "B.SilkS")
		)
		(fp_line
			(start 1.524 0.762)
			(end 1.524 -0.762)
			(stroke
				(width 0.1524)
				(type default)
			)
			(layer "B.SilkS")
		)
		(fp_line
			(start -1.524 -0.762)
			(end -1.524 0.762)
			(stroke
				(width 0.1524)
				(type default)
			)
			(layer "B.SilkS")
		)
		(fp_line
			(start 1.524 -0.762)
			(end -1.524 -0.762)
			(stroke
				(width 0.1524)
				(type default)
			)
			(layer "B.SilkS")
		)
		(fp_line
			(start -1.1049 0.724916)
			(end -1.1049 -0.724916)
			(stroke
				(width 0.1)
				(type default)
			)
			(layer "B.Fab")
		)
		(fp_line
			(start 1.1049 0.724916)
			(end -1.1049 0.724916)
			(stroke
				(width 0.1)
				(type default)
			)
			(layer "B.Fab")
		)
		(fp_line
			(start -1.1049 -0.724916)
			(end 1.1049 -0.724916)
			(stroke
				(width 0.1)
				(type default)
			)
			(layer "B.Fab")
		)
		(fp_line
			(start 1.1049 -0.724916)
			(end 1.1049 0.724916)
			(stroke
				(width 0.1)
				(type default)
			)
			(layer "B.Fab")
		)
		(pad "1" smd rect
			(at 0.889 0 270)
			(size 1.016 1.27)
			(layers "B.Cu" "B.Mask" "B.Paste")
			(net "PVCCIN_CPU0")
		)
		(pad "2" smd rect
			(at -0.889 0 270)
			(size 1.016 1.27)
			(layers "B.Cu" "B.Mask" "B.Paste")
			(net "GND")
		)
	)
)
